(kicad_pcb
	(version 20260206)
	(generator "pcbnew")
	(generator_version "10.0")
	(general
		(thickness 1.6)
		(legacy_teardrops no)
	)
	(paper "A4")
	(title_block
		(title "dpb — 14545-sa.0730WZS0815.brd")
		(comment 1 "Honey Badger (Wiwynn) / footprints 596-602 of 1066")
	)
	(layers
		(0 "F.Cu" signal "TOP")
		(4 "In1.Cu" signal "L2GND")
		(6 "In2.Cu" signal "L3")
		(8 "In3.Cu" signal "L4VCC")
		(10 "In4.Cu" signal "L5VCC")
		(12 "In5.Cu" signal "L6")
		(14 "In6.Cu" signal "L7GND")
		(2 "B.Cu" signal "BOTTOM")
		(9 "F.Adhes" user "F.Adhesive")
		(11 "B.Adhes" user "B.Adhesive")
		(13 "F.Paste" user "Package Geometry/Pastemask Top")
		(15 "B.Paste" user "Package Geometry/Pastemask Bottom")
		(5 "F.SilkS" user "Ref Des/Silkscreen Top")
		(7 "B.SilkS" user "Ref Des/Silkscreen Bottom")
		(1 "F.Mask" user "Board Geometry/Soldermask Top")
		(3 "B.Mask" user "Board Geometry/Soldermask Bottom")
		(17 "Dwgs.User" user "User.Drawings")
		(19 "Cmts.User" user "User.Comments")
		(21 "Eco1.User" user "User.Eco1")
		(23 "Eco2.User" user "User.Eco2")
		(25 "Edge.Cuts" user "Board Geometry/Outline")
		(27 "Margin" user)
		(31 "F.CrtYd" user "Package Geometry/Place Bound Top")
		(29 "B.CrtYd" user "Package Geometry/Place Bound Bottom")
		(35 "F.Fab" user "Ref Des/Assembly Top")
		(33 "B.Fab" user "Ref Des/Assembly Bottom")
	)
	(footprint ""
		(layer "F.Cu")
		(at 217.854784 -166.340028 -90)
		(property "Reference" "C152"
			(at 0 0 270)
			(layer "F.SilkS")
			(hide yes)
			(effects
				(font
					(size 1.27 1.27)
				)
			)
		)
		(property "Value" "SCD01U50V2KX-1GP"
			(at 1.1811 -2.7051 270)
			(unlocked yes)
			(layer "F.Fab")
			(hide yes)
			(effects
				(font
					(size 1.016 1.016)
					(thickness 0.1524)
				)
			)
		)
		(property "Device Type" "C402H22"
			(at 1.1811 -4.2291 270)
			(unlocked yes)
			(layer "F.Fab")
			(hide yes)
			(effects
				(font
					(size 1.016 1.016)
					(thickness 0.1524)
				)
			)
		)
		(duplicate_pad_numbers_are_jumpers no)
		(fp_rect
			(start -0.4318 0.9525)
			(end 0.4318 -0.9525)
			(stroke
				(width 0)
				(type default)
			)
			(fill no)
			(layer "F.CrtYd")
		)
		(fp_rect
			(start -0.4318 0.9525)
			(end 0.4318 -0.9525)
			(stroke
				(width 0)
				(type default)
			)
			(fill no)
			(layer "F.Fab")
		)
		(pad "1" smd custom
			(at 0 -0.4445 270)
			(size 0.1524 0.1524)
			(layers "F.Cu" "F.Mask" "F.Paste")
			(net "SAS2X28_DRIVE_RX_N_B3")
			(options
				(clearance outline)
				(anchor circle)
			)
			(primitives
				(gr_poly
					(pts
						(arc
							(start 0.3048 -0.2032)
							(mid 0.275042 -0.275042)
							(end 0.2032 -0.3048)
						)
						(arc
							(start -0.2032 -0.3048)
							(mid -0.275042 -0.275042)
							(end -0.3048 -0.2032)
						)
						(arc
							(start -0.3048 0.2032)
							(mid -0.275042 0.275042)
							(end -0.2032 0.3048)
						)
						(arc
							(start 0.2032 0.3048)
							(mid 0.275042 0.275042)
							(end 0.3048 0.2032)
						)
					)
					(width 0)
					(fill yes)
				)
			)
		)
		(pad "2" smd custom
			(at 0 0.4445 270)
			(size 0.1524 0.1524)
			(layers "F.Cu" "F.Mask" "F.Paste")
			(net "SAS2X28_B_HDD3_RX_-")
			(options
				(clearance outline)
				(anchor circle)
			)
			(primitives
				(gr_poly
					(pts
						(arc
							(start 0.3048 -0.2032)
							(mid 0.275042 -0.275042)
							(end 0.2032 -0.3048)
						)
						(arc
							(start -0.2032 -0.3048)
							(mid -0.275042 -0.275042)
							(end -0.3048 -0.2032)
						)
						(arc
							(start -0.3048 0.2032)
							(mid -0.275042 0.275042)
							(end -0.2032 0.3048)
						)
						(arc
							(start 0.2032 0.3048)
							(mid 0.275042 0.275042)
							(end 0.3048 0.2032)
						)
					)
					(width 0)
					(fill yes)
				)
			)
		)
	)
	(footprint ""
		(layer "F.Cu")
		(at 216.941654 -437.3245 180)
		(property "Reference" "PL7"
			(at 0 0 180)
			(layer "F.SilkS")
			(hide yes)
			(effects
				(font
					(size 1.27 1.27)
				)
			)
		)
		(property "Value" "IND-22UH-169-GP"
			(at -4.7498 0.5588 180)
			(unlocked yes)
			(layer "F.Fab")
			(hide yes)
			(effects
				(font
					(size 1.016 1.016)
					(thickness 0.1524)
				)
			)
		)
		(property "Device Type" "L6362-D620H119"
			(at -4.7498 -0.9652 180)
			(unlocked yes)
			(layer "F.Fab")
			(hide yes)
			(effects
				(font
					(size 1.016 1.016)
					(thickness 0.1524)
				)
			)
		)
		(duplicate_pad_numbers_are_jumpers no)
		(fp_line
			(start 3.3528 2.213356)
			(end 1.667256 3.8989)
			(stroke
				(width 0.1524)
				(type default)
			)
			(layer "F.SilkS")
		)
		(fp_line
			(start 3.3528 -2.213356)
			(end 3.3528 2.213356)
			(stroke
				(width 0.1524)
				(type default)
			)
			(layer "F.SilkS")
		)
		(fp_line
			(start 1.667256 3.8989)
			(end -1.667256 3.8989)
			(stroke
				(width 0.1524)
				(type default)
			)
			(layer "F.SilkS")
		)
		(fp_line
			(start 1.667256 -3.8989)
			(end 3.3528 -2.213356)
			(stroke
				(width 0.1524)
				(type default)
			)
			(layer "F.SilkS")
		)
		(fp_line
			(start -1.667256 3.8989)
			(end -3.3528 2.213356)
			(stroke
				(width 0.1524)
				(type default)
			)
			(layer "F.SilkS")
		)
		(fp_line
			(start -1.667256 -3.8989)
			(end 1.667256 -3.8989)
			(stroke
				(width 0.1524)
				(type default)
			)
			(layer "F.SilkS")
		)
		(fp_line
			(start -3.3528 2.213356)
			(end -3.3528 -2.213356)
			(stroke
				(width 0.1524)
				(type default)
			)
			(layer "F.SilkS")
		)
		(fp_line
			(start -3.3528 -2.213356)
			(end -1.667256 -3.8989)
			(stroke
				(width 0.1524)
				(type default)
			)
			(layer "F.SilkS")
		)
		(fp_poly
			(pts
				(xy 2.0574 3.1496) (xy -2.0574 3.1496) (xy -3.0988 2.1082) (xy -3.0988 -2.1082) (xy -2.0574 -3.1496)
				(xy 2.0574 -3.1496) (xy 3.0988 -2.1082) (xy 3.0988 2.1082)
			)
			(stroke
				(width 0)
				(type default)
			)
			(fill no)
			(layer "F.CrtYd")
		)
		(fp_poly
			(pts
				(xy 3.6068 2.318512) (xy 1.950212 3.9751) (xy -1.950212 3.9751) (xy -3.6068 2.318512) (xy -3.6068 -2.318512)
				(xy -1.950212 -3.9751) (xy 1.950212 -3.9751) (xy 3.6068 -2.318512) (xy 3.6068 -1.9177) (xy 3.0988 -1.9177)
				(xy 3.0988 -2.1082) (xy 2.0574 -3.1496) (xy -2.0574 -3.1496) (xy -3.0988 -2.1082) (xy -3.0988 2.1082)
				(xy -2.0574 3.1496) (xy 2.0574 3.1496) (xy 3.0988 2.1082) (xy 3.0988 -1.905) (xy 3.6068 -1.905)
			)
			(stroke
				(width 0)
				(type default)
			)
			(fill no)
			(layer "F.CrtYd")
		)
		(fp_poly
			(pts
				(xy -1.950212 3.9751) (xy -3.6068 2.318512) (xy -3.6068 -2.318512) (xy -1.950212 -3.9751) (xy 1.950212 -3.9751)
				(xy 3.6068 -2.318512) (xy 3.6068 2.318512) (xy 1.950212 3.9751)
			)
			(stroke
				(width 0)
				(type default)
			)
			(fill no)
			(layer "F.Fab")
		)
		(pad "1" smd rect
			(at 0 -2.895346 180)
			(size 2.2606 1.4986)
			(layers "F.Cu" "F.Mask" "F.Paste")
			(net "P3V3_LX")
		)
		(pad "2" smd rect
			(at 0 2.895346 180)
			(size 2.2606 1.4986)
			(layers "F.Cu" "F.Mask" "F.Paste")
			(net "P3V3_LX_COOPER")
		)
	)
	(footprint ""
		(layer "F.Cu")
		(at 44.068746 -230.279702 90)
		(property "Reference" "R273"
			(at 0 0 90)
			(layer "F.SilkS")
			(hide yes)
			(effects
				(font
					(size 1.27 1.27)
				)
			)
		)
		(property "Value" "2R2010J-1-GP"
			(at 0.254 -8.0772 90)
			(unlocked yes)
			(layer "F.Fab")
			(hide yes)
			(effects
				(font
					(size 1.016 1.016)
					(thickness 0.1524)
				)
			)
		)
		(property "Device Type" "R2010H28"
			(at 0.254 -9.6774 90)
			(unlocked yes)
			(layer "F.Fab")
			(hide yes)
			(effects
				(font
					(size 1.016 1.016)
					(thickness 0.1524)
				)
			)
		)
		(duplicate_pad_numbers_are_jumpers no)
		(fp_line
			(start 1.651 -3.302)
			(end -1.651 -3.302)
			(stroke
				(width 0.1524)
				(type default)
			)
			(layer "F.SilkS")
		)
		(fp_line
			(start -1.651 -3.302)
			(end -1.651 3.302)
			(stroke
				(width 0.1524)
				(type default)
			)
			(layer "F.SilkS")
		)
		(fp_line
			(start 1.651 3.302)
			(end 1.651 -3.302)
			(stroke
				(width 0.1524)
				(type default)
			)
			(layer "F.SilkS")
		)
		(fp_line
			(start -1.651 3.302)
			(end 1.651 3.302)
			(stroke
				(width 0.1524)
				(type default)
			)
			(layer "F.SilkS")
		)
		(fp_rect
			(start -1.7272 -3.3782)
			(end 1.7272 3.3782)
			(stroke
				(width 0)
				(type default)
			)
			(fill no)
			(layer "F.CrtYd")
		)
		(fp_poly
			(pts
				(xy 1.7272 3.3782) (xy 1.7272 -3.3782) (xy -1.7272 -3.3782) (xy -1.7272 3.3782)
			)
			(stroke
				(width 0)
				(type default)
			)
			(fill no)
			(layer "F.Fab")
		)
		(pad "1" smd rect
			(at 0 -2.3495 90)
			(size 2.794 1.143)
			(layers "F.Cu" "F.Mask" "F.Paste")
			(net "5V_PRE_12")
		)
		(pad "2" smd rect
			(at 0 2.3495 90)
			(size 2.794 1.143)
			(layers "F.Cu" "F.Mask" "F.Paste")
			(net "P5V_HDD12")
		)
	)
	(footprint ""
		(layer "F.Cu")
		(at 38.163246 -129.060702 90)
		(property "Reference" "R289"
			(at 0 0 90)
			(layer "F.SilkS")
			(hide yes)
			(effects
				(font
					(size 1.27 1.27)
				)
			)
		)
		(property "Value" "2R2010J-1-GP"
			(at 0.254 -8.0772 90)
			(unlocked yes)
			(layer "F.Fab")
			(hide yes)
			(effects
				(font
					(size 1.016 1.016)
					(thickness 0.1524)
				)
			)
		)
		(property "Device Type" "R2010H28"
			(at 0.254 -9.6774 90)
			(unlocked yes)
			(layer "F.Fab")
			(hide yes)
			(effects
				(font
					(size 1.016 1.016)
					(thickness 0.1524)
				)
			)
		)
		(duplicate_pad_numbers_are_jumpers no)
		(fp_line
			(start 1.651 -3.302)
			(end -1.651 -3.302)
			(stroke
				(width 0.1524)
				(type default)
			)
			(layer "F.SilkS")
		)
		(fp_line
			(start -1.651 -3.302)
			(end -1.651 3.302)
			(stroke
				(width 0.1524)
				(type default)
			)
			(layer "F.SilkS")
		)
		(fp_line
			(start 1.651 3.302)
			(end 1.651 -3.302)
			(stroke
				(width 0.1524)
				(type default)
			)
			(layer "F.SilkS")
		)
		(fp_line
			(start -1.651 3.302)
			(end 1.651 3.302)
			(stroke
				(width 0.1524)
				(type default)
			)
			(layer "F.SilkS")
		)
		(fp_rect
			(start -1.7272 -3.3782)
			(end 1.7272 3.3782)
			(stroke
				(width 0)
				(type default)
			)
			(fill no)
			(layer "F.CrtYd")
		)
		(fp_poly
			(pts
				(xy 1.7272 3.3782) (xy 1.7272 -3.3782) (xy -1.7272 -3.3782) (xy -1.7272 3.3782)
			)
			(stroke
				(width 0)
				(type default)
			)
			(fill no)
			(layer "F.Fab")
		)
		(pad "1" smd rect
			(at 0 -2.3495 90)
			(size 2.794 1.143)
			(layers "F.Cu" "F.Mask" "F.Paste")
			(net "5V_PRE_13")
		)
		(pad "2" smd rect
			(at 0 2.3495 90)
			(size 2.794 1.143)
			(layers "F.Cu" "F.Mask" "F.Paste")
			(net "P5V_HDD13")
		)
	)
	(footprint ""
		(layer "F.Cu")
		(at 230.364284 -143.988028 90)
		(property "Reference" "R144"
			(at 0 0 90)
			(layer "F.SilkS")
			(hide yes)
			(effects
				(font
					(size 1.27 1.27)
				)
			)
		)
		(property "Value" "0R2J-2-GP"
			(at 0.064008 -3.993896 90)
			(unlocked yes)
			(layer "F.Fab")
			(hide yes)
			(effects
				(font
					(size 1.016 1.016)
					(thickness 0.1524)
				)
			)
		)
		(property "Device Type" "R402H16"
			(at 0.064008 -5.517896 90)
			(unlocked yes)
			(layer "F.Fab")
			(hide yes)
			(effects
				(font
					(size 1.016 1.016)
					(thickness 0.1524)
				)
			)
		)
		(duplicate_pad_numbers_are_jumpers no)
		(fp_line
			(start 0.508 -0.9398)
			(end -0.508 -0.9398)
			(stroke
				(width 0.1524)
				(type default)
			)
			(layer "F.SilkS")
		)
		(fp_line
			(start -0.508 -0.9398)
			(end -0.508 0.9398)
			(stroke
				(width 0.1524)
				(type default)
			)
			(layer "F.SilkS")
		)
		(fp_rect
			(start -0.508 0.9398)
			(end 0.508 -0.9398)
			(stroke
				(width 0)
				(type default)
			)
			(fill no)
			(layer "F.CrtYd")
		)
		(fp_rect
			(start -0.508 0.9398)
			(end 0.508 -0.9398)
			(stroke
				(width 0)
				(type default)
			)
			(fill no)
			(layer "F.Fab")
		)
		(pad "1" smd custom
			(at 0 -0.4445 90)
			(size 0.1397 0.1397)
			(layers "F.Cu" "F.Mask" "F.Paste")
			(net "DRV_ACT_NET3")
			(options
				(clearance outline)
				(anchor circle)
			)
			(primitives
				(gr_poly
					(pts
						(arc
							(start -0.1778 -0.2794)
							(mid -0.249642 -0.249642)
							(end -0.2794 -0.1778)
						)
						(arc
							(start -0.2794 0.1778)
							(mid -0.249642 0.249642)
							(end -0.1778 0.2794)
						)
						(arc
							(start 0.1778 0.2794)
							(mid 0.249642 0.249642)
							(end 0.2794 0.1778)
						)
						(arc
							(start 0.2794 -0.1778)
							(mid 0.249642 -0.249642)
							(end 0.1778 -0.2794)
						)
					)
					(width 0)
					(fill yes)
				)
			)
		)
		(pad "2" smd custom
			(at 0 0.4445 90)
			(size 0.1397 0.1397)
			(layers "F.Cu" "F.Mask" "F.Paste")
			(net "DRIVE_ACT_3")
			(options
				(clearance outline)
				(anchor circle)
			)
			(primitives
				(gr_poly
					(pts
						(arc
							(start -0.1778 -0.2794)
							(mid -0.249642 -0.249642)
							(end -0.2794 -0.1778)
						)
						(arc
							(start -0.2794 0.1778)
							(mid -0.249642 0.249642)
							(end -0.1778 0.2794)
						)
						(arc
							(start 0.1778 0.2794)
							(mid 0.249642 0.249642)
							(end 0.2794 0.1778)
						)
						(arc
							(start 0.2794 -0.1778)
							(mid 0.249642 -0.249642)
							(end 0.1778 -0.2794)
						)
					)
					(width 0)
					(fill yes)
				)
			)
		)
	)
	(footprint ""
		(layer "F.Cu")
		(at 61.5442 -68.5038 -90)
		(property "Reference" "R395"
			(at 0 0 270)
			(layer "F.SilkS")
			(hide yes)
			(effects
				(font
					(size 1.27 1.27)
				)
			)
		)
		(property "Value" "10KR2F-2-GP"
			(at 0.064008 -3.993896 270)
			(unlocked yes)
			(layer "F.Fab")
			(hide yes)
			(effects
				(font
					(size 1.016 1.016)
					(thickness 0.1524)
				)
			)
		)
		(property "Device Type" "R402H16"
			(at 0.064008 -5.517896 270)
			(unlocked yes)
			(layer "F.Fab")
			(hide yes)
			(effects
				(font
					(size 1.016 1.016)
					(thickness 0.1524)
				)
			)
		)
		(duplicate_pad_numbers_are_jumpers no)
		(fp_line
			(start -0.508 -0.9398)
			(end -0.508 0.9398)
			(stroke
				(width 0.1524)
				(type default)
			)
			(layer "F.SilkS")
		)
		(fp_line
			(start 0.508 -0.9398)
			(end -0.508 -0.9398)
			(stroke
				(width 0.1524)
				(type default)
			)
			(layer "F.SilkS")
		)
		(fp_rect
			(start -0.508 0.9398)
			(end 0.508 -0.9398)
			(stroke
				(width 0)
				(type default)
			)
			(fill no)
			(layer "F.CrtYd")
		)
		(fp_rect
			(start -0.508 0.9398)
			(end 0.508 -0.9398)
			(stroke
				(width 0)
				(type default)
			)
			(fill no)
			(layer "F.Fab")
		)
		(pad "1" smd custom
			(at 0 -0.4445 270)
			(size 0.1397 0.1397)
			(layers "F.Cu" "F.Mask" "F.Paste")
			(net "P12V")
			(options
				(clearance outline)
				(anchor circle)
			)
			(primitives
				(gr_poly
					(pts
						(arc
							(start -0.1778 -0.2794)
							(mid -0.249642 -0.249642)
							(end -0.2794 -0.1778)
						)
						(arc
							(start -0.2794 0.1778)
							(mid -0.249642 0.249642)
							(end -0.1778 0.2794)
						)
						(arc
							(start 0.1778 0.2794)
							(mid 0.249642 0.249642)
							(end 0.2794 0.1778)
						)
						(arc
							(start 0.2794 -0.1778)
							(mid 0.249642 -0.249642)
							(end 0.1778 -0.2794)
						)
					)
					(width 0)
					(fill yes)
				)
			)
		)
		(pad "2" smd custom
			(at 0 0.4445 270)
			(size 0.1397 0.1397)
			(layers "F.Cu" "F.Mask" "F.Paste")
			(net "HDD9_LED_G")
			(options
				(clearance outline)
				(anchor circle)
			)
			(primitives
				(gr_poly
					(pts
						(arc
							(start -0.1778 -0.2794)
							(mid -0.249642 -0.249642)
							(end -0.2794 -0.1778)
						)
						(arc
							(start -0.2794 0.1778)
							(mid -0.249642 0.249642)
							(end -0.1778 0.2794)
						)
						(arc
							(start 0.1778 0.2794)
							(mid 0.249642 0.249642)
							(end 0.2794 0.1778)
						)
						(arc
							(start 0.2794 -0.1778)
							(mid 0.249642 -0.249642)
							(end 0.1778 -0.2794)
						)
					)
					(width 0)
					(fill yes)
				)
			)
		)
	)
	(footprint ""
		(layer "F.Cu")
		(at 46.8884 -349.1992 180)
		(property "Reference" "R185"
			(at 0 0 180)
			(layer "F.SilkS")
			(hide yes)
			(effects
				(font
					(size 1.27 1.27)
				)
			)
		)
		(property "Value" "402R2F-GP"
			(at 0.064008 -3.993896 180)
			(unlocked yes)
			(layer "F.Fab")
			(hide yes)
			(effects
				(font
					(size 1.016 1.016)
					(thickness 0.1524)
				)
			)
		)
		(property "Device Type" "R402H16"
			(at 0.064008 -5.517896 180)
			(unlocked yes)
			(layer "F.Fab")
			(hide yes)
			(effects
				(font
					(size 1.016 1.016)
					(thickness 0.1524)
				)
			)
		)
		(duplicate_pad_numbers_are_jumpers no)
		(fp_line
			(start 0.508 -0.9398)
			(end -0.508 -0.9398)
			(stroke
				(width 0.1524)
				(type default)
			)
			(layer "F.SilkS")
		)
		(fp_line
			(start -0.508 -0.9398)
			(end -0.508 0.9398)
			(stroke
				(width 0.1524)
				(type default)
			)
			(layer "F.SilkS")
		)
		(fp_rect
			(start -0.508 0.9398)
			(end 0.508 -0.9398)
			(stroke
				(width 0)
				(type default)
			)
			(fill no)
			(layer "F.CrtYd")
		)
		(fp_rect
			(start -0.508 0.9398)
			(end 0.508 -0.9398)
			(stroke
				(width 0)
				(type default)
			)
			(fill no)
			(layer "F.Fab")
		)
		(pad "1" smd custom
			(at 0 -0.4445 180)
			(size 0.1397 0.1397)
			(layers "F.Cu" "F.Mask" "F.Paste")
			(net "P5VB_HDD6_LED")
			(options
				(clearance outline)
				(anchor circle)
			)
			(primitives
				(gr_poly
					(pts
						(arc
							(start -0.1778 -0.2794)
							(mid -0.249642 -0.249642)
							(end -0.2794 -0.1778)
						)
						(arc
							(start -0.2794 0.1778)
							(mid -0.249642 0.249642)
							(end -0.1778 0.2794)
						)
						(arc
							(start 0.1778 0.2794)
							(mid 0.249642 0.249642)
							(end 0.2794 0.1778)
						)
						(arc
							(start 0.2794 -0.1778)
							(mid 0.249642 -0.249642)
							(end 0.1778 -0.2794)
						)
					)
					(width 0)
					(fill yes)
				)
			)
		)
		(pad "2" smd custom
			(at 0 0.4445 180)
			(size 0.1397 0.1397)
			(layers "F.Cu" "F.Mask" "F.Paste")
			(net "DRV_ACT_6")
			(options
				(clearance outline)
				(anchor circle)
			)
			(primitives
				(gr_poly
					(pts
						(arc
							(start -0.1778 -0.2794)
							(mid -0.249642 -0.249642)
							(end -0.2794 -0.1778)
						)
						(arc
							(start -0.2794 0.1778)
							(mid -0.249642 0.249642)
							(end -0.1778 0.2794)
						)
						(arc
							(start 0.1778 0.2794)
							(mid 0.249642 0.249642)
							(end 0.2794 0.1778)
						)
						(arc
							(start 0.2794 -0.1778)
							(mid 0.249642 -0.249642)
							(end 0.1778 -0.2794)
						)
					)
					(width 0)
					(fill yes)
				)
			)
		)
	)
)
